FILE_TYPE=LIBRARY_PARTS;
primitive 'TTL1G07_A','TTL1G07_A_SOP','TTL1G07_A_SOP1','TTL1G07_A_SOT353','TTL1G07_A_SOT23';
  pin
    'A':
      PIN_NUMBER='(2)';
      INPUT_LOAD='(-0.01,0.01)';
    'Y':
      PIN_NUMBER='(4)';
      OUTPUT_LOAD='(1.00,-1.00)';
  end_pin;
  body
    PART_NAME='TTL1G07_A';
    PHYS_DES_PREFIX='U';
    POWER_PINS='(VCC:5)';
    POWER_PINS='(GND:3)';
    NC_PINS='(1)';
  end_body;
end_primitive;

END.
